# T6G (Grand Teton) — schematic netlist excerpt (pin names and nets, part order shuffled) for the footprints in the layout excerpt that follows; sources: Cadence DE-HDL packaged netlist, KiCad conversion of 04192023_DAF0TMB3IC0_F0TG_MB_C_brd_V02_OCP.brd

R8100  Q_RES  0 5% CHIP  pkg 0402LF  page 147 : A = P3V3_E1S_PWRGD_0_R1 ; B = P3V3_E1S_PWRGD_0_R
R6743  Q_RES  1K 1% EMPTY  pkg 0402LF  page 358 : A = P1V8_AUX ; B = RT_BOARD_ID_ID0

(kicad_pcb
	(version 20260206)
	(generator "pcbnew")
	(generator_version "10.0")
	(general
		(thickness 1.6)
		(legacy_teardrops no)
	)
	(paper "A4")
	(title_block
		(title "04192023_DAF0TMB3IC0_F0TG_MB_C_brd_V02_OCP.brd")
		(comment 1 "Grand Teton / footprints 1090-1091 of 8354")
	)
	(layers
		(0 "F.Cu" signal "TOP")
		(4 "In1.Cu" signal "GND")
		(6 "In2.Cu" signal "IN1")
		(8 "In3.Cu" signal "GND1")
		(10 "In4.Cu" signal "IN2")
		(12 "In5.Cu" signal "GND2")
		(14 "In6.Cu" signal "IN3")
		(16 "In7.Cu" signal "GND3")
		(18 "In8.Cu" signal "VCC")
		(20 "In9.Cu" signal "VCC1")
		(22 "In10.Cu" signal "GND4")
		(24 "In11.Cu" signal "IN4")
		(26 "In12.Cu" signal "GND5")
		(28 "In13.Cu" signal "IN5")
		(30 "In14.Cu" signal "GND6")
		(32 "In15.Cu" signal "IN6")
		(34 "In16.Cu" signal "GND7")
		(2 "B.Cu" signal "BOTTOM")
		(9 "F.Adhes" user "F.Adhesive")
		(11 "B.Adhes" user "B.Adhesive")
		(13 "F.Paste" user "Package Geometry/Pastemask Top")
		(15 "B.Paste" user "Package Geometry/Pastemask Bottom")
		(5 "F.SilkS" user "Ref Des/Silkscreen Top")
		(7 "B.SilkS" user "Ref Des/Silkscreen Bottom")
		(1 "F.Mask" user "Board Geometry/Soldermask Top")
		(3 "B.Mask" user "Board Geometry/Soldermask Bottom")
		(17 "Dwgs.User" user "User.Drawings")
		(19 "Cmts.User" user "User.Comments")
		(21 "Eco1.User" user "User.Eco1")
		(23 "Eco2.User" user "User.Eco2")
		(25 "Edge.Cuts" user "Board Geometry/Outline")
		(27 "Margin" user)
		(31 "F.CrtYd" user "Package Geometry/Place Bound Top")
		(29 "B.CrtYd" user "Package Geometry/Place Bound Bottom")
		(35 "F.Fab" user "Ref Des/Assembly Top")
		(33 "B.Fab" user "Ref Des/Assembly Bottom")
	)
	(footprint ""
		(layer "F.Cu")
		(at 175.11776 -92.685616 90)
		(property "Reference" "R6743"
			(at 0 0 90)
			(layer "F.SilkS")
			(hide yes)
			(effects
				(font
					(size 1.27 1.27)
				)
			)
		)
		(property "Value" ""
			(at 0 0 90)
			(layer "F.Fab")
			(effects
				(font
					(size 1.27 1.27)
				)
			)
		)
		(duplicate_pad_numbers_are_jumpers no)
		(fp_line
			(start 0.7874 -0.4064)
			(end 0.7874 0.4064)
			(stroke
				(width 0.1524)
				(type default)
			)
			(layer "F.SilkS")
		)
		(fp_line
			(start -0.7874 -0.4064)
			(end 0.7874 -0.4064)
			(stroke
				(width 0.1524)
				(type default)
			)
			(layer "F.SilkS")
		)
		(fp_line
			(start 0.7874 0.4064)
			(end -0.7874 0.4064)
			(stroke
				(width 0.1524)
				(type default)
			)
			(layer "F.SilkS")
		)
		(fp_line
			(start -0.7874 0.4064)
			(end -0.7874 -0.4064)
			(stroke
				(width 0.1524)
				(type default)
			)
			(layer "F.SilkS")
		)
		(fp_line
			(start -0.12065 -0.305054)
			(end -0.12065 -0.2794)
			(stroke
				(width 0.1)
				(type default)
			)
			(layer "F.Fab")
		)
		(fp_line
			(start -0.67945 -0.305054)
			(end -0.12065 -0.305054)
			(stroke
				(width 0.1)
				(type default)
			)
			(layer "F.Fab")
		)
		(fp_line
			(start 0.67945 -0.3048)
			(end 0.67945 0.3048)
			(stroke
				(width 0.1)
				(type default)
			)
			(layer "F.Fab")
		)
		(fp_line
			(start 0.12065 -0.3048)
			(end 0.67945 -0.3048)
			(stroke
				(width 0.1)
				(type default)
			)
			(layer "F.Fab")
		)
		(fp_line
			(start 0.12065 -0.2794)
			(end 0.12065 -0.3048)
			(stroke
				(width 0.1)
				(type default)
			)
			(layer "F.Fab")
		)
		(fp_line
			(start -0.12065 -0.2794)
			(end 0.12065 -0.2794)
			(stroke
				(width 0.1)
				(type default)
			)
			(layer "F.Fab")
		)
		(fp_line
			(start 0.120396 0.2794)
			(end -0.12065 0.2794)
			(stroke
				(width 0.1)
				(type default)
			)
			(layer "F.Fab")
		)
		(fp_line
			(start -0.12065 0.2794)
			(end -0.12065 0.3048)
			(stroke
				(width 0.1)
				(type default)
			)
			(layer "F.Fab")
		)
		(fp_line
			(start 0.67945 0.3048)
			(end 0.120396 0.3048)
			(stroke
				(width 0.1)
				(type default)
			)
			(layer "F.Fab")
		)
		(fp_line
			(start 0.120396 0.3048)
			(end 0.120396 0.2794)
			(stroke
				(width 0.1)
				(type default)
			)
			(layer "F.Fab")
		)
		(fp_line
			(start -0.12065 0.3048)
			(end -0.67945 0.3048)
			(stroke
				(width 0.1)
				(type default)
			)
			(layer "F.Fab")
		)
		(fp_line
			(start -0.67945 0.3048)
			(end -0.67945 -0.305054)
			(stroke
				(width 0.1)
				(type default)
			)
			(layer "F.Fab")
		)
		(pad "1" smd circle
			(at -0.40005 0 90)
			(size 0 0)
			(layers "F.Cu" "F.Mask" "F.Paste")
			(net "P1V8_AUX")
		)
		(pad "2" smd circle
			(at 0.40005 0 90)
			(size 0 0)
			(layers "F.Cu" "F.Mask" "F.Paste")
			(net "RT_BOARD_ID_ID0")
		)
	)
	(footprint ""
		(layer "F.Cu")
		(at 225.171 -82.804)
		(property "Reference" "R8100"
			(at 0 0 0)
			(layer "F.SilkS")
			(hide yes)
			(effects
				(font
					(size 1.27 1.27)
				)
			)
		)
		(property "Value" ""
			(at 0 0 0)
			(layer "F.Fab")
			(effects
				(font
					(size 1.27 1.27)
				)
			)
		)
		(duplicate_pad_numbers_are_jumpers no)
		(fp_line
			(start -0.7874 -0.4064)
			(end 0.7874 -0.4064)
			(stroke
				(width 0.1524)
				(type default)
			)
			(layer "F.SilkS")
		)
		(fp_line
			(start -0.7874 0.4064)
			(end -0.7874 -0.4064)
			(stroke
				(width 0.1524)
				(type default)
			)
			(layer "F.SilkS")
		)
		(fp_line
			(start 0.7874 -0.4064)
			(end 0.7874 0.4064)
			(stroke
				(width 0.1524)
				(type default)
			)
			(layer "F.SilkS")
		)
		(fp_line
			(start 0.7874 0.4064)
			(end -0.7874 0.4064)
			(stroke
				(width 0.1524)
				(type default)
			)
			(layer "F.SilkS")
		)
		(fp_line
			(start -0.67945 -0.305054)
			(end -0.12065 -0.305054)
			(stroke
				(width 0.1)
				(type default)
			)
			(layer "F.Fab")
		)
		(fp_line
			(start -0.67945 0.3048)
			(end -0.67945 -0.305054)
			(stroke
				(width 0.1)
				(type default)
			)
			(layer "F.Fab")
		)
		(fp_line
			(start -0.12065 -0.305054)
			(end -0.12065 -0.2794)
			(stroke
				(width 0.1)
				(type default)
			)
			(layer "F.Fab")
		)
		(fp_line
			(start -0.12065 -0.2794)
			(end 0.12065 -0.2794)
			(stroke
				(width 0.1)
				(type default)
			)
			(layer "F.Fab")
		)
		(fp_line
			(start -0.12065 0.2794)
			(end -0.12065 0.3048)
			(stroke
				(width 0.1)
				(type default)
			)
			(layer "F.Fab")
		)
		(fp_line
			(start -0.12065 0.3048)
			(end -0.67945 0.3048)
			(stroke
				(width 0.1)
				(type default)
			)
			(layer "F.Fab")
		)
		(fp_line
			(start 0.120396 0.2794)
			(end -0.12065 0.2794)
			(stroke
				(width 0.1)
				(type default)
			)
			(layer "F.Fab")
		)
		(fp_line
			(start 0.120396 0.3048)
			(end 0.120396 0.2794)
			(stroke
				(width 0.1)
				(type default)
			)
			(layer "F.Fab")
		)
		(fp_line
			(start 0.12065 -0.3048)
			(end 0.67945 -0.3048)
			(stroke
				(width 0.1)
				(type default)
			)
			(layer "F.Fab")
		)
		(fp_line
			(start 0.12065 -0.2794)
			(end 0.12065 -0.3048)
			(stroke
				(width 0.1)
				(type default)
			)
			(layer "F.Fab")
		)
		(fp_line
			(start 0.67945 -0.3048)
			(end 0.67945 0.3048)
			(stroke
				(width 0.1)
				(type default)
			)
			(layer "F.Fab")
		)
		(fp_line
			(start 0.67945 0.3048)
			(end 0.120396 0.3048)
			(stroke
				(width 0.1)
				(type default)
			)
			(layer "F.Fab")
		)
		(pad "1" smd circle
			(at -0.40005 0)
			(size 0 0)
			(layers "F.Cu" "F.Mask" "F.Paste")
			(net "P3V3_E1S_PWRGD_0_R1")
		)
		(pad "2" smd circle
			(at 0.40005 0)
			(size 0 0)
			(layers "F.Cu" "F.Mask" "F.Paste")
			(net "P3V3_E1S_PWRGD_0_R")
		)
	)
)
